# S9S_MB_2U (Grand Teton) — schematic netlist excerpt (pin names and nets, part order shuffled) for the footprints in the layout excerpt that follows; sources: Cadence DE-HDL packaged netlist, KiCad conversion of 03242023_DA0F0TMBIJ0_F0T_Motherboard_J_brd_V01_OCP.brd

R4775  Q_RES  5.11K 1% EMPTY  pkg 0402LF  page 307 : A = P12V_AUX_UV_ADR_TRIGGER ; B = GND
PR216  Q_RES  0 5% CHIP  pkg 0402LF  page 296 : A = SH_PVCCD_HV_CPU1 ; B = SH_PVCCD_HV_CPU1_R

(kicad_pcb
	(version 20260206)
	(generator "pcbnew")
	(generator_version "10.0")
	(general
		(thickness 1.6)
		(legacy_teardrops no)
	)
	(paper "A4")
	(title_block
		(title "03242023_DA0F0TMBIJ0_F0T_Motherboard_J_brd_V01_OCP.brd")
		(comment 1 "Grand Teton / footprints 3322-3323 of 6105")
	)
	(layers
		(0 "F.Cu" signal "TOP")
		(4 "In1.Cu" signal "GND")
		(6 "In2.Cu" signal "IN1")
		(8 "In3.Cu" signal "GND1")
		(10 "In4.Cu" signal "IN2")
		(12 "In5.Cu" signal "GND2")
		(14 "In6.Cu" signal "IN3")
		(16 "In7.Cu" signal "GND3")
		(18 "In8.Cu" signal "VCC")
		(20 "In9.Cu" signal "VCC1")
		(22 "In10.Cu" signal "GND4")
		(24 "In11.Cu" signal "IN4")
		(26 "In12.Cu" signal "GND5")
		(28 "In13.Cu" signal "IN5")
		(30 "In14.Cu" signal "GND6")
		(32 "In15.Cu" signal "IN6")
		(34 "In16.Cu" signal "GND7")
		(2 "B.Cu" signal "BOTTOM")
		(9 "F.Adhes" user "F.Adhesive")
		(11 "B.Adhes" user "B.Adhesive")
		(13 "F.Paste" user "Package Geometry/Pastemask Top")
		(15 "B.Paste" user "Package Geometry/Pastemask Bottom")
		(5 "F.SilkS" user "Ref Des/Silkscreen Top")
		(7 "B.SilkS" user "Ref Des/Silkscreen Bottom")
		(1 "F.Mask" user "Board Geometry/Soldermask Top")
		(3 "B.Mask" user "Board Geometry/Soldermask Bottom")
		(17 "Dwgs.User" user "User.Drawings")
		(19 "Cmts.User" user "User.Comments")
		(21 "Eco1.User" user "User.Eco1")
		(23 "Eco2.User" user "User.Eco2")
		(25 "Edge.Cuts" user "Board Geometry/Outline")
		(27 "Margin" user)
		(31 "F.CrtYd" user "Package Geometry/Place Bound Top")
		(29 "B.CrtYd" user "Package Geometry/Place Bound Bottom")
		(35 "F.Fab" user "Ref Des/Assembly Top")
		(33 "B.Fab" user "Ref Des/Assembly Bottom")
	)
	(footprint ""
		(layer "F.Cu")
		(at 205.6892 -92.6338 -90)
		(property "Reference" "R4775"
			(at 0 0 270)
			(layer "F.SilkS")
			(hide yes)
			(effects
				(font
					(size 1.27 1.27)
				)
			)
		)
		(property "Value" ""
			(at 0 0 270)
			(layer "F.Fab")
			(effects
				(font
					(size 1.27 1.27)
				)
			)
		)
		(duplicate_pad_numbers_are_jumpers no)
		(fp_line
			(start -0.7874 0.4064)
			(end -0.7874 -0.4064)
			(stroke
				(width 0.1524)
				(type default)
			)
			(layer "F.SilkS")
		)
		(fp_line
			(start 0.7874 0.4064)
			(end -0.7874 0.4064)
			(stroke
				(width 0.1524)
				(type default)
			)
			(layer "F.SilkS")
		)
		(fp_line
			(start -0.7874 -0.4064)
			(end 0.7874 -0.4064)
			(stroke
				(width 0.1524)
				(type default)
			)
			(layer "F.SilkS")
		)
		(fp_line
			(start 0.7874 -0.4064)
			(end 0.7874 0.4064)
			(stroke
				(width 0.1524)
				(type default)
			)
			(layer "F.SilkS")
		)
		(fp_line
			(start -0.67945 0.3048)
			(end -0.67945 -0.305054)
			(stroke
				(width 0.1)
				(type default)
			)
			(layer "F.Fab")
		)
		(fp_line
			(start -0.12065 0.3048)
			(end -0.67945 0.3048)
			(stroke
				(width 0.1)
				(type default)
			)
			(layer "F.Fab")
		)
		(fp_line
			(start 0.120396 0.3048)
			(end 0.120396 0.2794)
			(stroke
				(width 0.1)
				(type default)
			)
			(layer "F.Fab")
		)
		(fp_line
			(start 0.67945 0.3048)
			(end 0.120396 0.3048)
			(stroke
				(width 0.1)
				(type default)
			)
			(layer "F.Fab")
		)
		(fp_line
			(start -0.12065 0.2794)
			(end -0.12065 0.3048)
			(stroke
				(width 0.1)
				(type default)
			)
			(layer "F.Fab")
		)
		(fp_line
			(start 0.120396 0.2794)
			(end -0.12065 0.2794)
			(stroke
				(width 0.1)
				(type default)
			)
			(layer "F.Fab")
		)
		(fp_line
			(start -0.12065 -0.2794)
			(end 0.12065 -0.2794)
			(stroke
				(width 0.1)
				(type default)
			)
			(layer "F.Fab")
		)
		(fp_line
			(start 0.12065 -0.2794)
			(end 0.12065 -0.3048)
			(stroke
				(width 0.1)
				(type default)
			)
			(layer "F.Fab")
		)
		(fp_line
			(start 0.12065 -0.3048)
			(end 0.67945 -0.3048)
			(stroke
				(width 0.1)
				(type default)
			)
			(layer "F.Fab")
		)
		(fp_line
			(start 0.67945 -0.3048)
			(end 0.67945 0.3048)
			(stroke
				(width 0.1)
				(type default)
			)
			(layer "F.Fab")
		)
		(fp_line
			(start -0.67945 -0.305054)
			(end -0.12065 -0.305054)
			(stroke
				(width 0.1)
				(type default)
			)
			(layer "F.Fab")
		)
		(fp_line
			(start -0.12065 -0.305054)
			(end -0.12065 -0.2794)
			(stroke
				(width 0.1)
				(type default)
			)
			(layer "F.Fab")
		)
		(pad "1" smd circle
			(at -0.40005 0 270)
			(size 0 0)
			(layers "F.Cu" "F.Mask" "F.Paste")
			(net "P12V_AUX_UV_ADR_TRIGGER")
		)
		(pad "2" smd circle
			(at 0.40005 0 270)
			(size 0 0)
			(layers "F.Cu" "F.Mask" "F.Paste")
			(net "GND")
		)
	)
	(footprint ""
		(layer "F.Cu")
		(at 21.920708 -162.20567 90)
		(property "Reference" "PR216"
			(at 0 0 90)
			(layer "F.SilkS")
			(hide yes)
			(effects
				(font
					(size 1.27 1.27)
				)
			)
		)
		(property "Value" ""
			(at 0 0 90)
			(layer "F.Fab")
			(effects
				(font
					(size 1.27 1.27)
				)
			)
		)
		(duplicate_pad_numbers_are_jumpers no)
		(fp_line
			(start 0.7874 -0.4064)
			(end 0.7874 0.4064)
			(stroke
				(width 0.1524)
				(type default)
			)
			(layer "F.SilkS")
		)
		(fp_line
			(start -0.7874 -0.4064)
			(end 0.7874 -0.4064)
			(stroke
				(width 0.1524)
				(type default)
			)
			(layer "F.SilkS")
		)
		(fp_line
			(start 0.7874 0.4064)
			(end -0.7874 0.4064)
			(stroke
				(width 0.1524)
				(type default)
			)
			(layer "F.SilkS")
		)
		(fp_line
			(start -0.7874 0.4064)
			(end -0.7874 -0.4064)
			(stroke
				(width 0.1524)
				(type default)
			)
			(layer "F.SilkS")
		)
		(fp_line
			(start -0.12065 -0.305054)
			(end -0.12065 -0.2794)
			(stroke
				(width 0.1)
				(type default)
			)
			(layer "F.Fab")
		)
		(fp_line
			(start -0.67945 -0.305054)
			(end -0.12065 -0.305054)
			(stroke
				(width 0.1)
				(type default)
			)
			(layer "F.Fab")
		)
		(fp_line
			(start 0.67945 -0.3048)
			(end 0.67945 0.3048)
			(stroke
				(width 0.1)
				(type default)
			)
			(layer "F.Fab")
		)
		(fp_line
			(start 0.12065 -0.3048)
			(end 0.67945 -0.3048)
			(stroke
				(width 0.1)
				(type default)
			)
			(layer "F.Fab")
		)
		(fp_line
			(start 0.12065 -0.2794)
			(end 0.12065 -0.3048)
			(stroke
				(width 0.1)
				(type default)
			)
			(layer "F.Fab")
		)
		(fp_line
			(start -0.12065 -0.2794)
			(end 0.12065 -0.2794)
			(stroke
				(width 0.1)
				(type default)
			)
			(layer "F.Fab")
		)
		(fp_line
			(start 0.120396 0.2794)
			(end -0.12065 0.2794)
			(stroke
				(width 0.1)
				(type default)
			)
			(layer "F.Fab")
		)
		(fp_line
			(start -0.12065 0.2794)
			(end -0.12065 0.3048)
			(stroke
				(width 0.1)
				(type default)
			)
			(layer "F.Fab")
		)
		(fp_line
			(start 0.67945 0.3048)
			(end 0.120396 0.3048)
			(stroke
				(width 0.1)
				(type default)
			)
			(layer "F.Fab")
		)
		(fp_line
			(start 0.120396 0.3048)
			(end 0.120396 0.2794)
			(stroke
				(width 0.1)
				(type default)
			)
			(layer "F.Fab")
		)
		(fp_line
			(start -0.12065 0.3048)
			(end -0.67945 0.3048)
			(stroke
				(width 0.1)
				(type default)
			)
			(layer "F.Fab")
		)
		(fp_line
			(start -0.67945 0.3048)
			(end -0.67945 -0.305054)
			(stroke
				(width 0.1)
				(type default)
			)
			(layer "F.Fab")
		)
		(pad "1" smd circle
			(at -0.40005 0 90)
			(size 0 0)
			(layers "F.Cu" "F.Mask" "F.Paste")
			(net "SH_PVCCD_HV_CPU1")
		)
		(pad "2" smd circle
			(at 0.40005 0 90)
			(size 0 0)
			(layers "F.Cu" "F.Mask" "F.Paste")
			(net "SH_PVCCD_HV_CPU1_R")
		)
	)
)
